# T6G (Grand Teton) — schematic netlist excerpt (pin names and nets, part order shuffled) for the footprints in the layout excerpt that follows; sources: Cadence DE-HDL packaged netlist, KiCad conversion of 04192023_DAF0TMB3IC0_F0TG_MB_C_brd_V02_OCP.brd

C2302  Q_CAP  22UF 4V 20% X6S  pkg C0402  page 73 : A = PVDDCR_CPU0_P1 ; B = GND
C512  Q_CAP  1UF 4V 20% X6S  pkg 0201  page 279 : A = P1V8_CPU0_RT0_1A ; B = GND
R3771  Q_RES  10K 1% CHIP  pkg 0402LF  page 145 : A = P3V3_AUX ; B = E1S_0_PWRDIS

(kicad_pcb
	(version 20260206)
	(generator "pcbnew")
	(generator_version "10.0")
	(general
		(thickness 1.6)
		(legacy_teardrops no)
	)
	(paper "A4")
	(title_block
		(title "04192023_DAF0TMB3IC0_F0TG_MB_C_brd_V02_OCP.brd")
		(comment 1 "Grand Teton / footprints 6951-6953 of 8354")
	)
	(layers
		(0 "F.Cu" signal "TOP")
		(4 "In1.Cu" signal "GND")
		(6 "In2.Cu" signal "IN1")
		(8 "In3.Cu" signal "GND1")
		(10 "In4.Cu" signal "IN2")
		(12 "In5.Cu" signal "GND2")
		(14 "In6.Cu" signal "IN3")
		(16 "In7.Cu" signal "GND3")
		(18 "In8.Cu" signal "VCC")
		(20 "In9.Cu" signal "VCC1")
		(22 "In10.Cu" signal "GND4")
		(24 "In11.Cu" signal "IN4")
		(26 "In12.Cu" signal "GND5")
		(28 "In13.Cu" signal "IN5")
		(30 "In14.Cu" signal "GND6")
		(32 "In15.Cu" signal "IN6")
		(34 "In16.Cu" signal "GND7")
		(2 "B.Cu" signal "BOTTOM")
		(9 "F.Adhes" user "F.Adhesive")
		(11 "B.Adhes" user "B.Adhesive")
		(13 "F.Paste" user "Package Geometry/Pastemask Top")
		(15 "B.Paste" user "Package Geometry/Pastemask Bottom")
		(5 "F.SilkS" user "Ref Des/Silkscreen Top")
		(7 "B.SilkS" user "Ref Des/Silkscreen Bottom")
		(1 "F.Mask" user "Board Geometry/Soldermask Top")
		(3 "B.Mask" user "Board Geometry/Soldermask Bottom")
		(17 "Dwgs.User" user "User.Drawings")
		(19 "Cmts.User" user "User.Comments")
		(21 "Eco1.User" user "User.Eco1")
		(23 "Eco2.User" user "User.Eco2")
		(25 "Edge.Cuts" user "Board Geometry/Outline")
		(27 "Margin" user)
		(31 "F.CrtYd" user "Package Geometry/Place Bound Top")
		(29 "B.CrtYd" user "Package Geometry/Place Bound Bottom")
		(35 "F.Fab" user "Ref Des/Assembly Top")
		(33 "B.Fab" user "Ref Des/Assembly Bottom")
	)
	(footprint ""
		(layer "B.Cu")
		(at 115.991386 -250.892564)
		(property "Reference" "C2302"
			(at 0 0 0)
			(layer "B.SilkS")
			(hide yes)
			(effects
				(font
					(size 1.27 1.27)
				)
				(justify mirror)
			)
		)
		(property "Value" ""
			(at 0 0 0)
			(layer "B.Fab")
			(effects
				(font
					(size 1.27 1.27)
				)
				(justify mirror)
			)
		)
		(duplicate_pad_numbers_are_jumpers no)
		(fp_line
			(start -0.7874 -0.4064)
			(end -0.7874 0.4064)
			(stroke
				(width 0.1524)
				(type default)
			)
			(layer "B.SilkS")
		)
		(fp_line
			(start -0.7874 0.4064)
			(end 0.7874 0.4064)
			(stroke
				(width 0.1524)
				(type default)
			)
			(layer "B.SilkS")
		)
		(fp_line
			(start 0.7874 -0.4064)
			(end -0.7874 -0.4064)
			(stroke
				(width 0.1524)
				(type default)
			)
			(layer "B.SilkS")
		)
		(fp_line
			(start 0.7874 0.4064)
			(end 0.7874 -0.4064)
			(stroke
				(width 0.1524)
				(type default)
			)
			(layer "B.SilkS")
		)
		(fp_line
			(start -0.67945 -0.3048)
			(end -0.67945 0.3048)
			(stroke
				(width 0.1)
				(type default)
			)
			(layer "B.Fab")
		)
		(fp_line
			(start -0.67945 0.3048)
			(end -0.120396 0.3048)
			(stroke
				(width 0.1)
				(type default)
			)
			(layer "B.Fab")
		)
		(fp_line
			(start -0.12065 -0.3048)
			(end -0.67945 -0.3048)
			(stroke
				(width 0.1)
				(type default)
			)
			(layer "B.Fab")
		)
		(fp_line
			(start -0.12065 -0.2794)
			(end -0.12065 -0.3048)
			(stroke
				(width 0.1)
				(type default)
			)
			(layer "B.Fab")
		)
		(fp_line
			(start -0.120396 0.2794)
			(end 0.12065 0.2794)
			(stroke
				(width 0.1)
				(type default)
			)
			(layer "B.Fab")
		)
		(fp_line
			(start -0.120396 0.3048)
			(end -0.120396 0.2794)
			(stroke
				(width 0.1)
				(type default)
			)
			(layer "B.Fab")
		)
		(fp_line
			(start 0.12065 -0.305054)
			(end 0.12065 -0.2794)
			(stroke
				(width 0.1)
				(type default)
			)
			(layer "B.Fab")
		)
		(fp_line
			(start 0.12065 -0.2794)
			(end -0.12065 -0.2794)
			(stroke
				(width 0.1)
				(type default)
			)
			(layer "B.Fab")
		)
		(fp_line
			(start 0.12065 0.2794)
			(end 0.12065 0.3048)
			(stroke
				(width 0.1)
				(type default)
			)
			(layer "B.Fab")
		)
		(fp_line
			(start 0.12065 0.3048)
			(end 0.67945 0.3048)
			(stroke
				(width 0.1)
				(type default)
			)
			(layer "B.Fab")
		)
		(fp_line
			(start 0.67945 -0.305054)
			(end 0.12065 -0.305054)
			(stroke
				(width 0.1)
				(type default)
			)
			(layer "B.Fab")
		)
		(fp_line
			(start 0.67945 0.3048)
			(end 0.67945 -0.305054)
			(stroke
				(width 0.1)
				(type default)
			)
			(layer "B.Fab")
		)
		(pad "1" smd circle
			(at 0.40005 0 180)
			(size 0 0)
			(layers "B.Cu" "B.Mask" "B.Paste")
			(net "PVDDCR_CPU0_P1")
		)
		(pad "2" smd circle
			(at -0.40005 0 180)
			(size 0 0)
			(layers "B.Cu" "B.Mask" "B.Paste")
			(net "GND")
		)
	)
	(footprint ""
		(layer "B.Cu")
		(at 310.7182 -396.393162 -90)
		(property "Reference" "C512"
			(at 0 0 90)
			(layer "B.SilkS")
			(hide yes)
			(effects
				(font
					(size 1.27 1.27)
				)
				(justify mirror)
			)
		)
		(property "Value" ""
			(at 0 0 90)
			(layer "B.Fab")
			(effects
				(font
					(size 1.27 1.27)
				)
				(justify mirror)
			)
		)
		(duplicate_pad_numbers_are_jumpers no)
		(fp_line
			(start -0.299974 0.150114)
			(end 0.299974 0.150114)
			(stroke
				(width 0.1)
				(type default)
			)
			(layer "B.Fab")
		)
		(fp_line
			(start 0.299974 0.150114)
			(end 0.299974 -0.150114)
			(stroke
				(width 0.1)
				(type default)
			)
			(layer "B.Fab")
		)
		(fp_line
			(start -0.299974 -0.150114)
			(end -0.299974 0.150114)
			(stroke
				(width 0.1)
				(type default)
			)
			(layer "B.Fab")
		)
		(fp_line
			(start 0.299974 -0.150114)
			(end -0.299974 -0.150114)
			(stroke
				(width 0.1)
				(type default)
			)
			(layer "B.Fab")
		)
		(pad "1" smd rect
			(at 0.2667 0 90)
			(size 0.3048 0.381)
			(layers "B.Cu" "B.Mask" "B.Paste")
			(net "P1V8_CPU0_RT0_1A")
		)
		(pad "2" smd rect
			(at -0.2667 0 90)
			(size 0.3048 0.381)
			(layers "B.Cu" "B.Mask" "B.Paste")
			(net "GND")
		)
	)
	(footprint ""
		(layer "B.Cu")
		(at 236.20095 -50.193448 180)
		(property "Reference" "R3771"
			(at 0 0 0)
			(layer "B.SilkS")
			(hide yes)
			(effects
				(font
					(size 1.27 1.27)
				)
				(justify mirror)
			)
		)
		(property "Value" ""
			(at 0 0 0)
			(layer "B.Fab")
			(effects
				(font
					(size 1.27 1.27)
				)
				(justify mirror)
			)
		)
		(duplicate_pad_numbers_are_jumpers no)
		(fp_line
			(start 0.7874 0.4064)
			(end 0.7874 -0.4064)
			(stroke
				(width 0.1524)
				(type default)
			)
			(layer "B.SilkS")
		)
		(fp_line
			(start 0.7874 -0.4064)
			(end -0.7874 -0.4064)
			(stroke
				(width 0.1524)
				(type default)
			)
			(layer "B.SilkS")
		)
		(fp_line
			(start -0.7874 0.4064)
			(end 0.7874 0.4064)
			(stroke
				(width 0.1524)
				(type default)
			)
			(layer "B.SilkS")
		)
		(fp_line
			(start -0.7874 -0.4064)
			(end -0.7874 0.4064)
			(stroke
				(width 0.1524)
				(type default)
			)
			(layer "B.SilkS")
		)
		(fp_line
			(start 0.67945 0.3048)
			(end 0.67945 -0.305054)
			(stroke
				(width 0.1)
				(type default)
			)
			(layer "B.Fab")
		)
		(fp_line
			(start 0.67945 -0.305054)
			(end 0.12065 -0.305054)
			(stroke
				(width 0.1)
				(type default)
			)
			(layer "B.Fab")
		)
		(fp_line
			(start 0.12065 0.3048)
			(end 0.67945 0.3048)
			(stroke
				(width 0.1)
				(type default)
			)
			(layer "B.Fab")
		)
		(fp_line
			(start 0.12065 0.2794)
			(end 0.12065 0.3048)
			(stroke
				(width 0.1)
				(type default)
			)
			(layer "B.Fab")
		)
		(fp_line
			(start 0.12065 -0.2794)
			(end -0.12065 -0.2794)
			(stroke
				(width 0.1)
				(type default)
			)
			(layer "B.Fab")
		)
		(fp_line
			(start 0.12065 -0.305054)
			(end 0.12065 -0.2794)
			(stroke
				(width 0.1)
				(type default)
			)
			(layer "B.Fab")
		)
		(fp_line
			(start -0.120396 0.3048)
			(end -0.120396 0.2794)
			(stroke
				(width 0.1)
				(type default)
			)
			(layer "B.Fab")
		)
		(fp_line
			(start -0.120396 0.2794)
			(end 0.12065 0.2794)
			(stroke
				(width 0.1)
				(type default)
			)
			(layer "B.Fab")
		)
		(fp_line
			(start -0.12065 -0.2794)
			(end -0.12065 -0.3048)
			(stroke
				(width 0.1)
				(type default)
			)
			(layer "B.Fab")
		)
		(fp_line
			(start -0.12065 -0.3048)
			(end -0.67945 -0.3048)
			(stroke
				(width 0.1)
				(type default)
			)
			(layer "B.Fab")
		)
		(fp_line
			(start -0.67945 0.3048)
			(end -0.120396 0.3048)
			(stroke
				(width 0.1)
				(type default)
			)
			(layer "B.Fab")
		)
		(fp_line
			(start -0.67945 -0.3048)
			(end -0.67945 0.3048)
			(stroke
				(width 0.1)
				(type default)
			)
			(layer "B.Fab")
		)
		(pad "1" smd circle
			(at 0.40005 0)
			(size 0 0)
			(layers "B.Cu" "B.Mask" "B.Paste")
			(net "P3V3_AUX")
		)
		(pad "2" smd circle
			(at -0.40005 0)
			(size 0 0)
			(layers "B.Cu" "B.Mask" "B.Paste")
			(net "E1S_0_PWRDIS")
		)
	)
)
